# BASEBOARD_FAB2 (Tioga Pass) — schematic netlist excerpt (pin names and nets, part order shuffled) for the footprints in the layout excerpt that follows; sources: Cadence DE-HDL packaged netlist, KiCad conversion of Wiwynn_Tioga_Pass_MB.brd

C2T18  CAP_A  0.01UF 25V 10% X7R  pkg 0402V  page 101 : A = P3V3_STBY_MNG_CPU ; B = GND
C9A6  CAP_A  1.0UF 6.3V 10% X6S  pkg 0402V  page 111 : A = P1V05_PCH_STBY ; B = GND
R4R6  RES  1.00K 1% CHIP  pkg 0402  page 113 : A = JTAG_MCP_CPU0_TDI_R ; B = JTAG_MCP_CPU0_TDI

(kicad_pcb
	(version 20260206)
	(generator "pcbnew")
	(generator_version "10.0")
	(general
		(thickness 1.6)
		(legacy_teardrops no)
	)
	(paper "A4")
	(title_block
		(title "Wiwynn_Tioga_Pass_MB.brd")
		(comment 1 "Tioga Pass / footprints 4076-4078 of 4770")
	)
	(layers
		(0 "F.Cu" signal "TOP")
		(4 "In1.Cu" signal "L2GND")
		(6 "In2.Cu" signal "L3")
		(8 "In3.Cu" signal "L4GND")
		(10 "In4.Cu" signal "L5")
		(12 "In5.Cu" signal "L6GND")
		(14 "In6.Cu" signal "L7VCC")
		(16 "In7.Cu" signal "L8VCC")
		(18 "In8.Cu" signal "L9GND")
		(20 "In9.Cu" signal "L10")
		(22 "In10.Cu" signal "L11GND")
		(24 "In11.Cu" signal "L12")
		(26 "In12.Cu" signal "L13GND")
		(2 "B.Cu" signal "BOTTOM")
		(9 "F.Adhes" user "F.Adhesive")
		(11 "B.Adhes" user "B.Adhesive")
		(13 "F.Paste" user "Package Geometry/Pastemask Top")
		(15 "B.Paste" user "Package Geometry/Pastemask Bottom")
		(5 "F.SilkS" user "Ref Des/Silkscreen Top")
		(7 "B.SilkS" user "Ref Des/Silkscreen Bottom")
		(1 "F.Mask" user "Board Geometry/Soldermask Top")
		(3 "B.Mask" user "Board Geometry/Soldermask Bottom")
		(17 "Dwgs.User" user "User.Drawings")
		(19 "Cmts.User" user "User.Comments")
		(21 "Eco1.User" user "User.Eco1")
		(23 "Eco2.User" user "User.Eco2")
		(25 "Edge.Cuts" user "Board Geometry/Outline")
		(27 "Margin" user)
		(31 "F.CrtYd" user "Package Geometry/Place Bound Top")
		(29 "B.CrtYd" user "Package Geometry/Place Bound Bottom")
		(35 "F.Fab" user "Ref Des/Assembly Top")
		(33 "B.Fab" user "Ref Des/Assembly Bottom")
	)
	(footprint ""
		(layer "B.Cu")
		(at 328.041 -55.626 -90)
		(property "Reference" "R4R6"
			(at 0 0 90)
			(layer "B.SilkS")
			(hide yes)
			(effects
				(font
					(size 1.27 1.27)
				)
				(justify mirror)
			)
		)
		(property "Value" ""
			(at 0 0 90)
			(layer "B.Fab")
			(effects
				(font
					(size 1.27 1.27)
				)
				(justify mirror)
			)
		)
		(duplicate_pad_numbers_are_jumpers no)
		(fp_poly
			(pts
				(xy 0.2794 -0.1016) (xy -0.2794 -0.1016) (xy -0.2794 0.9906) (xy 0.2794 0.9906)
			)
			(stroke
				(width 0)
				(type default)
			)
			(fill no)
			(layer "B.CrtYd")
		)
		(fp_line
			(start -0.2794 0.9906)
			(end -0.2794 -0.1016)
			(stroke
				(width 0.1)
				(type default)
			)
			(layer "B.Fab")
		)
		(fp_line
			(start 0.2794 0.9906)
			(end -0.2794 0.9906)
			(stroke
				(width 0.1)
				(type default)
			)
			(layer "B.Fab")
		)
		(fp_line
			(start -0.2794 -0.1016)
			(end 0.2794 -0.1016)
			(stroke
				(width 0.1)
				(type default)
			)
			(layer "B.Fab")
		)
		(fp_line
			(start 0.2794 -0.1016)
			(end 0.2794 0.9906)
			(stroke
				(width 0.1)
				(type default)
			)
			(layer "B.Fab")
		)
		(pad "1" smd rect
			(at 0 0 90)
			(size 0.508 0.508)
			(layers "B.Cu" "B.Mask" "B.Paste")
			(net "JTAG_MCP_CPU0_TDI_R")
		)
		(pad "2" smd rect
			(at 0 0.889 90)
			(size 0.508 0.508)
			(layers "B.Cu" "B.Mask" "B.Paste")
			(net "JTAG_MCP_CPU0_TDI")
		)
		(zone
			(layer "B.Cu")
			(hatch none 0.5)
			(connect_pads
				(clearance 0)
			)
			(min_thickness 0.25)
			(keepout
				(tracks not_allowed)
				(vias allowed)
				(pads allowed)
				(copperpour not_allowed)
				(footprints allowed)
			)
			(placement
				(enabled no)
				(sheetname "")
			)
			(fill
				(thermal_gap 0.5)
				(thermal_bridge_width 0.5)
				(island_removal_mode 0)
			)
			(polygon
				(pts
					(xy 327.406 -55.372) (xy 327.406 -55.88) (xy 327.787 -55.88) (xy 327.787 -55.372)
				)
			)
		)
		(zone
			(layer "B.Cu")
			(hatch none 0.5)
			(connect_pads
				(clearance 0)
			)
			(min_thickness 0.25)
			(keepout
				(tracks allowed)
				(vias not_allowed)
				(pads allowed)
				(copperpour not_allowed)
				(footprints allowed)
			)
			(placement
				(enabled no)
				(sheetname "")
			)
			(fill
				(thermal_gap 0.5)
				(thermal_bridge_width 0.5)
				(island_removal_mode 0)
			)
			(polygon
				(pts
					(xy 327.787 -55.372) (xy 327.787 -55.88) (xy 327.406 -55.88) (xy 327.406 -55.372)
				)
			)
		)
	)
	(footprint ""
		(layer "B.Cu")
		(at 454.787 -142.0114)
		(property "Reference" "C9A6"
			(at 0 0 0)
			(layer "B.SilkS")
			(hide yes)
			(effects
				(font
					(size 1.27 1.27)
				)
				(justify mirror)
			)
		)
		(property "Value" ""
			(at 0 0 0)
			(layer "B.Fab")
			(effects
				(font
					(size 1.27 1.27)
				)
				(justify mirror)
			)
		)
		(duplicate_pad_numbers_are_jumpers no)
		(fp_poly
			(pts
				(xy -0.3048 -0.1016) (xy -0.3048 0.9906) (xy 0.3048 0.9906) (xy 0.3048 -0.1016)
			)
			(stroke
				(width 0)
				(type default)
			)
			(fill no)
			(layer "B.CrtYd")
		)
		(fp_line
			(start -0.3048 -0.1016)
			(end 0.3048 -0.1016)
			(stroke
				(width 0.1)
				(type default)
			)
			(layer "B.Fab")
		)
		(fp_line
			(start -0.3048 0.9906)
			(end -0.3048 -0.1016)
			(stroke
				(width 0.1)
				(type default)
			)
			(layer "B.Fab")
		)
		(fp_line
			(start 0.3048 -0.1016)
			(end 0.3048 0.9906)
			(stroke
				(width 0.1)
				(type default)
			)
			(layer "B.Fab")
		)
		(fp_line
			(start 0.3048 0.9906)
			(end -0.3048 0.9906)
			(stroke
				(width 0.1)
				(type default)
			)
			(layer "B.Fab")
		)
		(pad "1" smd rect
			(at 0 0 180)
			(size 0.508 0.508)
			(layers "B.Cu" "B.Mask" "B.Paste")
			(net "P1V05_PCH_STBY")
		)
		(pad "2" smd rect
			(at 0 0.889 180)
			(size 0.508 0.508)
			(layers "B.Cu" "B.Mask" "B.Paste")
			(net "GND")
		)
		(zone
			(layer "B.Cu")
			(hatch none 0.5)
			(connect_pads
				(clearance 0)
			)
			(min_thickness 0.25)
			(keepout
				(tracks allowed)
				(vias not_allowed)
				(pads allowed)
				(copperpour not_allowed)
				(footprints allowed)
			)
			(placement
				(enabled no)
				(sheetname "")
			)
			(fill
				(thermal_gap 0.5)
				(thermal_bridge_width 0.5)
				(island_removal_mode 0)
			)
			(polygon
				(pts
					(xy 455.041 -141.7574) (xy 454.533 -141.7574) (xy 454.533 -141.3764) (xy 455.041 -141.3764)
				)
			)
		)
		(zone
			(layer "B.Cu")
			(hatch none 0.5)
			(connect_pads
				(clearance 0)
			)
			(min_thickness 0.25)
			(keepout
				(tracks not_allowed)
				(vias allowed)
				(pads allowed)
				(copperpour not_allowed)
				(footprints allowed)
			)
			(placement
				(enabled no)
				(sheetname "")
			)
			(fill
				(thermal_gap 0.5)
				(thermal_bridge_width 0.5)
				(island_removal_mode 0)
			)
			(polygon
				(pts
					(xy 455.041 -141.3764) (xy 454.533 -141.3764) (xy 454.533 -141.7574) (xy 455.041 -141.7574)
				)
			)
		)
	)
	(footprint ""
		(layer "B.Cu")
		(at 479.11766 -27.70632 180)
		(property "Reference" "C2T18"
			(at 0 0 0)
			(layer "B.SilkS")
			(hide yes)
			(effects
				(font
					(size 1.27 1.27)
				)
				(justify mirror)
			)
		)
		(property "Value" ""
			(at 0 0 0)
			(layer "B.Fab")
			(effects
				(font
					(size 1.27 1.27)
				)
				(justify mirror)
			)
		)
		(duplicate_pad_numbers_are_jumpers no)
		(fp_poly
			(pts
				(xy -0.3048 -0.1016) (xy -0.3048 0.9906) (xy 0.3048 0.9906) (xy 0.3048 -0.1016)
			)
			(stroke
				(width 0)
				(type default)
			)
			(fill no)
			(layer "B.CrtYd")
		)
		(fp_line
			(start 0.3048 0.9906)
			(end -0.3048 0.9906)
			(stroke
				(width 0.1)
				(type default)
			)
			(layer "B.Fab")
		)
		(fp_line
			(start 0.3048 -0.1016)
			(end 0.3048 0.9906)
			(stroke
				(width 0.1)
				(type default)
			)
			(layer "B.Fab")
		)
		(fp_line
			(start -0.3048 0.9906)
			(end -0.3048 -0.1016)
			(stroke
				(width 0.1)
				(type default)
			)
			(layer "B.Fab")
		)
		(fp_line
			(start -0.3048 -0.1016)
			(end 0.3048 -0.1016)
			(stroke
				(width 0.1)
				(type default)
			)
			(layer "B.Fab")
		)
		(pad "1" smd rect
			(at 0 0)
			(size 0.508 0.508)
			(layers "B.Cu" "B.Mask" "B.Paste")
			(net "P3V3_STBY_MNG_CPU")
		)
		(pad "2" smd rect
			(at 0 0.889)
			(size 0.508 0.508)
			(layers "B.Cu" "B.Mask" "B.Paste")
			(net "GND")
		)
		(zone
			(layer "B.Cu")
			(hatch none 0.5)
			(connect_pads
				(clearance 0)
			)
			(min_thickness 0.25)
			(keepout
				(tracks not_allowed)
				(vias allowed)
				(pads allowed)
				(copperpour not_allowed)
				(footprints allowed)
			)
			(placement
				(enabled no)
				(sheetname "")
			)
			(fill
				(thermal_gap 0.5)
				(thermal_bridge_width 0.5)
				(island_removal_mode 0)
			)
			(polygon
				(pts
					(xy 478.86366 -28.34132) (xy 479.37166 -28.34132) (xy 479.37166 -27.96032) (xy 478.86366 -27.96032)
				)
			)
		)
		(zone
			(layer "B.Cu")
			(hatch none 0.5)
			(connect_pads
				(clearance 0)
			)
			(min_thickness 0.25)
			(keepout
				(tracks allowed)
				(vias not_allowed)
				(pads allowed)
				(copperpour not_allowed)
				(footprints allowed)
			)
			(placement
				(enabled no)
				(sheetname "")
			)
			(fill
				(thermal_gap 0.5)
				(thermal_bridge_width 0.5)
				(island_removal_mode 0)
			)
			(polygon
				(pts
					(xy 478.86366 -27.96032) (xy 479.37166 -27.96032) (xy 479.37166 -28.34132) (xy 478.86366 -28.34132)
				)
			)
		)
	)
)
